# T6G (Grand Teton) — schematic netlist excerpt (pin names and nets, part order shuffled) for the footprints in the layout excerpt that follows; sources: Cadence DE-HDL packaged netlist, KiCad conversion of 04192023_DAF0TMB3IC0_F0TG_MB_C_brd_V02_OCP.brd

PR6526  Q_RES  10K 1% CHIP  pkg 0402LF  page 361 : A = P1V8_RETIMER_CPU1_FB ; B = GND
C1106  Q_CAP  0.1UF 25V 10% X7R  pkg 0402  page 357 : A = P3V3_AUX ; B = GND

(kicad_pcb
	(version 20260206)
	(generator "pcbnew")
	(generator_version "10.0")
	(general
		(thickness 1.6)
		(legacy_teardrops no)
	)
	(paper "A4")
	(title_block
		(title "04192023_DAF0TMB3IC0_F0TG_MB_C_brd_V02_OCP.brd")
		(comment 1 "Grand Teton / footprints 2283-2284 of 8354")
	)
	(layers
		(0 "F.Cu" signal "TOP")
		(4 "In1.Cu" signal "GND")
		(6 "In2.Cu" signal "IN1")
		(8 "In3.Cu" signal "GND1")
		(10 "In4.Cu" signal "IN2")
		(12 "In5.Cu" signal "GND2")
		(14 "In6.Cu" signal "IN3")
		(16 "In7.Cu" signal "GND3")
		(18 "In8.Cu" signal "VCC")
		(20 "In9.Cu" signal "VCC1")
		(22 "In10.Cu" signal "GND4")
		(24 "In11.Cu" signal "IN4")
		(26 "In12.Cu" signal "GND5")
		(28 "In13.Cu" signal "IN5")
		(30 "In14.Cu" signal "GND6")
		(32 "In15.Cu" signal "IN6")
		(34 "In16.Cu" signal "GND7")
		(2 "B.Cu" signal "BOTTOM")
		(9 "F.Adhes" user "F.Adhesive")
		(11 "B.Adhes" user "B.Adhesive")
		(13 "F.Paste" user "Package Geometry/Pastemask Top")
		(15 "B.Paste" user "Package Geometry/Pastemask Bottom")
		(5 "F.SilkS" user "Ref Des/Silkscreen Top")
		(7 "B.SilkS" user "Ref Des/Silkscreen Bottom")
		(1 "F.Mask" user "Board Geometry/Soldermask Top")
		(3 "B.Mask" user "Board Geometry/Soldermask Bottom")
		(17 "Dwgs.User" user "User.Drawings")
		(19 "Cmts.User" user "User.Comments")
		(21 "Eco1.User" user "User.Eco1")
		(23 "Eco2.User" user "User.Eco2")
		(25 "Edge.Cuts" user "Board Geometry/Outline")
		(27 "Margin" user)
		(31 "F.CrtYd" user "Package Geometry/Place Bound Top")
		(29 "B.CrtYd" user "Package Geometry/Place Bound Bottom")
		(35 "F.Fab" user "Ref Des/Assembly Top")
		(33 "B.Fab" user "Ref Des/Assembly Bottom")
	)
	(footprint ""
		(layer "F.Cu")
		(at 227.949252 -290.341812 89.946)
		(property "Reference" "PR6526"
			(at 0 0 89.946)
			(layer "F.SilkS")
			(hide yes)
			(effects
				(font
					(size 1.27 1.27)
				)
			)
		)
		(property "Value" ""
			(at 0 0 89.946)
			(layer "F.Fab")
			(effects
				(font
					(size 1.27 1.27)
				)
			)
		)
		(duplicate_pad_numbers_are_jumpers no)
		(fp_line
			(start -0.787275 -0.40642)
			(end 0.787525 -0.40638)
			(stroke
				(width 0.1524)
				(type default)
			)
			(layer "F.SilkS")
		)
		(fp_line
			(start 0.787525 -0.40638)
			(end 0.787275 0.40642)
			(stroke
				(width 0.1524)
				(type default)
			)
			(layer "F.SilkS")
		)
		(fp_line
			(start -0.787525 0.40638)
			(end -0.787275 -0.40642)
			(stroke
				(width 0.1524)
				(type default)
			)
			(layer "F.SilkS")
		)
		(fp_line
			(start 0.787275 0.40642)
			(end -0.787525 0.40638)
			(stroke
				(width 0.1524)
				(type default)
			)
			(layer "F.SilkS")
		)
		(fp_line
			(start -0.679484 -0.305176)
			(end -0.120683 -0.30494)
			(stroke
				(width 0.1)
				(type default)
			)
			(layer "F.Fab")
		)
		(fp_line
			(start -0.120683 -0.30494)
			(end -0.120659 -0.279286)
			(stroke
				(width 0.1)
				(type default)
			)
			(layer "F.Fab")
		)
		(fp_line
			(start 0.120617 -0.304914)
			(end 0.679417 -0.304678)
			(stroke
				(width 0.1)
				(type default)
			)
			(layer "F.Fab")
		)
		(fp_line
			(start 0.679417 -0.304678)
			(end 0.679484 0.304922)
			(stroke
				(width 0.1)
				(type default)
			)
			(layer "F.Fab")
		)
		(fp_line
			(start 0.120641 -0.279514)
			(end 0.120617 -0.304914)
			(stroke
				(width 0.1)
				(type default)
			)
			(layer "F.Fab")
		)
		(fp_line
			(start -0.120659 -0.279286)
			(end 0.120641 -0.279514)
			(stroke
				(width 0.1)
				(type default)
			)
			(layer "F.Fab")
		)
		(fp_line
			(start 0.120405 0.279287)
			(end -0.120641 0.279514)
			(stroke
				(width 0.1)
				(type default)
			)
			(layer "F.Fab")
		)
		(fp_line
			(start -0.120641 0.279514)
			(end -0.120617 0.304914)
			(stroke
				(width 0.1)
				(type default)
			)
			(layer "F.Fab")
		)
		(fp_line
			(start -0.679417 0.304678)
			(end -0.679484 -0.305176)
			(stroke
				(width 0.1)
				(type default)
			)
			(layer "F.Fab")
		)
		(fp_line
			(start 0.120429 0.304687)
			(end 0.120405 0.279287)
			(stroke
				(width 0.1)
				(type default)
			)
			(layer "F.Fab")
		)
		(fp_line
			(start -0.120617 0.304914)
			(end -0.679417 0.304678)
			(stroke
				(width 0.1)
				(type default)
			)
			(layer "F.Fab")
		)
		(fp_line
			(start 0.679484 0.304922)
			(end 0.120429 0.304687)
			(stroke
				(width 0.1)
				(type default)
			)
			(layer "F.Fab")
		)
		(pad "1" smd circle
			(at -0.40005 0 89.946)
			(size 0 0)
			(layers "F.Cu" "F.Mask" "F.Paste")
			(net "P1V8_RETIMER_CPU1_FB")
		)
		(pad "2" smd circle
			(at 0.40005 0 89.946)
			(size 0 0)
			(layers "F.Cu" "F.Mask" "F.Paste")
			(net "GND")
		)
	)
	(footprint ""
		(layer "F.Cu")
		(at 26.226516 -39.037514)
		(property "Reference" "C1106"
			(at 0 0 0)
			(layer "F.SilkS")
			(hide yes)
			(effects
				(font
					(size 1.27 1.27)
				)
			)
		)
		(property "Value" ""
			(at 0 0 0)
			(layer "F.Fab")
			(effects
				(font
					(size 1.27 1.27)
				)
			)
		)
		(duplicate_pad_numbers_are_jumpers no)
		(fp_line
			(start -0.7874 -0.4064)
			(end 0.7874 -0.4064)
			(stroke
				(width 0.1524)
				(type default)
			)
			(layer "F.SilkS")
		)
		(fp_line
			(start -0.7874 0.4064)
			(end -0.7874 -0.4064)
			(stroke
				(width 0.1524)
				(type default)
			)
			(layer "F.SilkS")
		)
		(fp_line
			(start 0.7874 -0.4064)
			(end 0.7874 0.4064)
			(stroke
				(width 0.1524)
				(type default)
			)
			(layer "F.SilkS")
		)
		(fp_line
			(start 0.7874 0.4064)
			(end -0.7874 0.4064)
			(stroke
				(width 0.1524)
				(type default)
			)
			(layer "F.SilkS")
		)
		(fp_line
			(start -0.67945 -0.305054)
			(end -0.12065 -0.305054)
			(stroke
				(width 0.1)
				(type default)
			)
			(layer "F.Fab")
		)
		(fp_line
			(start -0.67945 0.3048)
			(end -0.67945 -0.305054)
			(stroke
				(width 0.1)
				(type default)
			)
			(layer "F.Fab")
		)
		(fp_line
			(start -0.12065 -0.305054)
			(end -0.12065 -0.2794)
			(stroke
				(width 0.1)
				(type default)
			)
			(layer "F.Fab")
		)
		(fp_line
			(start -0.12065 -0.2794)
			(end 0.12065 -0.2794)
			(stroke
				(width 0.1)
				(type default)
			)
			(layer "F.Fab")
		)
		(fp_line
			(start -0.12065 0.2794)
			(end -0.12065 0.3048)
			(stroke
				(width 0.1)
				(type default)
			)
			(layer "F.Fab")
		)
		(fp_line
			(start -0.12065 0.3048)
			(end -0.67945 0.3048)
			(stroke
				(width 0.1)
				(type default)
			)
			(layer "F.Fab")
		)
		(fp_line
			(start 0.120396 0.2794)
			(end -0.12065 0.2794)
			(stroke
				(width 0.1)
				(type default)
			)
			(layer "F.Fab")
		)
		(fp_line
			(start 0.120396 0.3048)
			(end 0.120396 0.2794)
			(stroke
				(width 0.1)
				(type default)
			)
			(layer "F.Fab")
		)
		(fp_line
			(start 0.12065 -0.3048)
			(end 0.67945 -0.3048)
			(stroke
				(width 0.1)
				(type default)
			)
			(layer "F.Fab")
		)
		(fp_line
			(start 0.12065 -0.2794)
			(end 0.12065 -0.3048)
			(stroke
				(width 0.1)
				(type default)
			)
			(layer "F.Fab")
		)
		(fp_line
			(start 0.67945 -0.3048)
			(end 0.67945 0.3048)
			(stroke
				(width 0.1)
				(type default)
			)
			(layer "F.Fab")
		)
		(fp_line
			(start 0.67945 0.3048)
			(end 0.120396 0.3048)
			(stroke
				(width 0.1)
				(type default)
			)
			(layer "F.Fab")
		)
		(pad "1" smd circle
			(at -0.40005 0)
			(size 0 0)
			(layers "F.Cu" "F.Mask" "F.Paste")
			(net "P3V3_AUX")
		)
		(pad "2" smd circle
			(at 0.40005 0)
			(size 0 0)
			(layers "F.Cu" "F.Mask" "F.Paste")
			(net "GND")
		)
	)
)
